# T6G (Grand Teton) — schematic netlist excerpt (pin names and nets, part order shuffled) for the footprints in the layout excerpt that follows; sources: Cadence DE-HDL packaged netlist, KiCad conversion of 04192023_DAF0TMB3IC0_F0TG_MB_C_brd_V02_OCP.brd

PPQ7  MOSFET_NCH_1D3S  PSMNR58-30YLH IC  pkg SOT1023  page 266
  \1\  = P12V_AUX
  \2\  = P12V_AUX
  \3\  = P12V_AUX
  \4\  = P12V_HSC_GATE_G3
  \5\  = P12V_MAIN_R

R6288  Q_RES  1K 1% EMPTY  pkg 0402LF  page 178 : A = USB_HUB2_TI_PWRCTL_POL ; B = GND

(kicad_pcb
	(version 20260206)
	(generator "pcbnew")
	(generator_version "10.0")
	(general
		(thickness 1.6)
		(legacy_teardrops no)
	)
	(paper "A4")
	(title_block
		(title "04192023_DAF0TMB3IC0_F0TG_MB_C_brd_V02_OCP.brd")
		(comment 1 "Grand Teton / footprints 3722-3723 of 8354")
	)
	(layers
		(0 "F.Cu" signal "TOP")
		(4 "In1.Cu" signal "GND")
		(6 "In2.Cu" signal "IN1")
		(8 "In3.Cu" signal "GND1")
		(10 "In4.Cu" signal "IN2")
		(12 "In5.Cu" signal "GND2")
		(14 "In6.Cu" signal "IN3")
		(16 "In7.Cu" signal "GND3")
		(18 "In8.Cu" signal "VCC")
		(20 "In9.Cu" signal "VCC1")
		(22 "In10.Cu" signal "GND4")
		(24 "In11.Cu" signal "IN4")
		(26 "In12.Cu" signal "GND5")
		(28 "In13.Cu" signal "IN5")
		(30 "In14.Cu" signal "GND6")
		(32 "In15.Cu" signal "IN6")
		(34 "In16.Cu" signal "GND7")
		(2 "B.Cu" signal "BOTTOM")
		(9 "F.Adhes" user "F.Adhesive")
		(11 "B.Adhes" user "B.Adhesive")
		(13 "F.Paste" user "Package Geometry/Pastemask Top")
		(15 "B.Paste" user "Package Geometry/Pastemask Bottom")
		(5 "F.SilkS" user "Ref Des/Silkscreen Top")
		(7 "B.SilkS" user "Ref Des/Silkscreen Bottom")
		(1 "F.Mask" user "Board Geometry/Soldermask Top")
		(3 "B.Mask" user "Board Geometry/Soldermask Bottom")
		(17 "Dwgs.User" user "User.Drawings")
		(19 "Cmts.User" user "User.Comments")
		(21 "Eco1.User" user "User.Eco1")
		(23 "Eco2.User" user "User.Eco2")
		(25 "Edge.Cuts" user "Board Geometry/Outline")
		(27 "Margin" user)
		(31 "F.CrtYd" user "Package Geometry/Place Bound Top")
		(29 "B.CrtYd" user "Package Geometry/Place Bound Bottom")
		(35 "F.Fab" user "Ref Des/Assembly Top")
		(33 "B.Fab" user "Ref Des/Assembly Bottom")
	)
	(footprint ""
		(layer "F.Cu")
		(at 265.395964 -385.27736 90)
		(property "Reference" "PPQ7"
			(at -7.603236 -2.160524 0)
			(unlocked yes)
			(layer "F.SilkS")
			(effects
				(font
					(size 0.7874 0.5842)
					(thickness 0.1524)
				)
				(justify left)
			)
		)
		(property "Value" ""
			(at 0 0 90)
			(layer "F.Fab")
			(effects
				(font
					(size 1.27 1.27)
				)
			)
		)
		(duplicate_pad_numbers_are_jumpers no)
		(fp_line
			(start 2.350008 -2.649982)
			(end 2.350008 -2.4892)
			(stroke
				(width 0.1524)
				(type default)
			)
			(layer "F.SilkS")
		)
		(fp_line
			(start -2.350008 -2.649982)
			(end 2.350008 -2.649982)
			(stroke
				(width 0.1524)
				(type default)
			)
			(layer "F.SilkS")
		)
		(fp_line
			(start -2.350008 -2.4384)
			(end -2.350008 -2.649982)
			(stroke
				(width 0.1524)
				(type default)
			)
			(layer "F.SilkS")
		)
		(fp_line
			(start 2.350008 2.4892)
			(end 2.350008 2.649982)
			(stroke
				(width 0.1524)
				(type default)
			)
			(layer "F.SilkS")
		)
		(fp_line
			(start 2.350008 2.649982)
			(end -2.350008 2.649982)
			(stroke
				(width 0.1524)
				(type default)
			)
			(layer "F.SilkS")
		)
		(fp_line
			(start -2.350008 2.649982)
			(end -2.350008 2.413)
			(stroke
				(width 0.1524)
				(type default)
			)
			(layer "F.SilkS")
		)
		(fp_poly
			(pts
				(xy -3.447796 -3.466338) (xy -2.648712 -3.428238) (xy -3.116834 -2.40792)
			)
			(stroke
				(width 0)
				(type default)
			)
			(fill yes)
			(layer "F.SilkS")
		)
		(fp_line
			(start 2.350008 -2.649982)
			(end 2.350008 2.649982)
			(stroke
				(width 0.1)
				(type default)
			)
			(layer "F.Fab")
		)
		(fp_line
			(start -2.350008 -2.649982)
			(end 2.350008 -2.649982)
			(stroke
				(width 0.1)
				(type default)
			)
			(layer "F.Fab")
		)
		(fp_line
			(start 2.350008 2.649982)
			(end -2.350008 2.649982)
			(stroke
				(width 0.1)
				(type default)
			)
			(layer "F.Fab")
		)
		(fp_line
			(start -2.350008 2.649982)
			(end -2.350008 -2.649982)
			(stroke
				(width 0.1)
				(type default)
			)
			(layer "F.Fab")
		)
		(fp_poly
			(pts
				(xy -3.717544 -1.905) (xy -4.758944 -2.3241) (xy -4.758944 -1.524)
			)
			(stroke
				(width 0)
				(type default)
			)
			(fill yes)
			(layer "F.Fab")
		)
		(pad "1" smd rect
			(at -2.999994 -1.905)
			(size 0.7112 1.1684)
			(layers "F.Cu" "F.Mask" "F.Paste")
			(net "P12V_AUX")
		)
		(pad "2" smd rect
			(at -2.999994 -0.635)
			(size 0.7112 1.1684)
			(layers "F.Cu" "F.Mask" "F.Paste")
			(net "P12V_AUX")
		)
		(pad "3" smd rect
			(at -2.999994 0.635)
			(size 0.7112 1.1684)
			(layers "F.Cu" "F.Mask" "F.Paste")
			(net "P12V_AUX")
		)
		(pad "4" smd rect
			(at -2.999994 1.905)
			(size 0.7112 1.1684)
			(layers "F.Cu" "F.Mask" "F.Paste")
			(net "P12V_HSC_GATE_G3")
		)
		(pad "5" smd circle
			(at 0.925068 0)
			(size 0 0)
			(layers "F.Cu" "F.Mask" "F.Paste")
			(net "P12V_MAIN_R")
		)
		(zone
			(layer "F.Cu")
			(hatch none 0.5)
			(connect_pads
				(clearance 0)
			)
			(min_thickness 0.25)
			(keepout
				(tracks not_allowed)
				(vias allowed)
				(pads allowed)
				(copperpour not_allowed)
				(footprints allowed)
			)
			(placement
				(enabled no)
				(sheetname "")
			)
			(fill
				(thermal_gap 0.5)
				(thermal_bridge_width 0.5)
				(island_removal_mode 0)
			)
			(polygon
				(pts
					(xy 262.754364 -383.7178) (xy 268.037564 -383.7178) (xy 268.037564 -382.92786) (xy 262.754364 -382.92786)
				)
			)
		)
	)
	(footprint ""
		(layer "F.Cu")
		(at 112.267238 -41.17975 90)
		(property "Reference" "R6288"
			(at 0 0 90)
			(layer "F.SilkS")
			(hide yes)
			(effects
				(font
					(size 1.27 1.27)
				)
			)
		)
		(property "Value" ""
			(at 0 0 90)
			(layer "F.Fab")
			(effects
				(font
					(size 1.27 1.27)
				)
			)
		)
		(duplicate_pad_numbers_are_jumpers no)
		(fp_line
			(start 0.7874 -0.4064)
			(end 0.7874 0.4064)
			(stroke
				(width 0.1524)
				(type default)
			)
			(layer "F.SilkS")
		)
		(fp_line
			(start -0.7874 -0.4064)
			(end 0.7874 -0.4064)
			(stroke
				(width 0.1524)
				(type default)
			)
			(layer "F.SilkS")
		)
		(fp_line
			(start 0.7874 0.4064)
			(end -0.7874 0.4064)
			(stroke
				(width 0.1524)
				(type default)
			)
			(layer "F.SilkS")
		)
		(fp_line
			(start -0.7874 0.4064)
			(end -0.7874 -0.4064)
			(stroke
				(width 0.1524)
				(type default)
			)
			(layer "F.SilkS")
		)
		(fp_line
			(start -0.12065 -0.305054)
			(end -0.12065 -0.2794)
			(stroke
				(width 0.1)
				(type default)
			)
			(layer "F.Fab")
		)
		(fp_line
			(start -0.67945 -0.305054)
			(end -0.12065 -0.305054)
			(stroke
				(width 0.1)
				(type default)
			)
			(layer "F.Fab")
		)
		(fp_line
			(start 0.67945 -0.3048)
			(end 0.67945 0.3048)
			(stroke
				(width 0.1)
				(type default)
			)
			(layer "F.Fab")
		)
		(fp_line
			(start 0.12065 -0.3048)
			(end 0.67945 -0.3048)
			(stroke
				(width 0.1)
				(type default)
			)
			(layer "F.Fab")
		)
		(fp_line
			(start 0.12065 -0.2794)
			(end 0.12065 -0.3048)
			(stroke
				(width 0.1)
				(type default)
			)
			(layer "F.Fab")
		)
		(fp_line
			(start -0.12065 -0.2794)
			(end 0.12065 -0.2794)
			(stroke
				(width 0.1)
				(type default)
			)
			(layer "F.Fab")
		)
		(fp_line
			(start 0.120396 0.2794)
			(end -0.12065 0.2794)
			(stroke
				(width 0.1)
				(type default)
			)
			(layer "F.Fab")
		)
		(fp_line
			(start -0.12065 0.2794)
			(end -0.12065 0.3048)
			(stroke
				(width 0.1)
				(type default)
			)
			(layer "F.Fab")
		)
		(fp_line
			(start 0.67945 0.3048)
			(end 0.120396 0.3048)
			(stroke
				(width 0.1)
				(type default)
			)
			(layer "F.Fab")
		)
		(fp_line
			(start 0.120396 0.3048)
			(end 0.120396 0.2794)
			(stroke
				(width 0.1)
				(type default)
			)
			(layer "F.Fab")
		)
		(fp_line
			(start -0.12065 0.3048)
			(end -0.67945 0.3048)
			(stroke
				(width 0.1)
				(type default)
			)
			(layer "F.Fab")
		)
		(fp_line
			(start -0.67945 0.3048)
			(end -0.67945 -0.305054)
			(stroke
				(width 0.1)
				(type default)
			)
			(layer "F.Fab")
		)
		(pad "1" smd circle
			(at -0.40005 0 90)
			(size 0 0)
			(layers "F.Cu" "F.Mask" "F.Paste")
			(net "USB_HUB2_TI_PWRCTL_POL")
		)
		(pad "2" smd circle
			(at 0.40005 0 90)
			(size 0 0)
			(layers "F.Cu" "F.Mask" "F.Paste")
			(net "GND")
		)
	)
)
